(kicad_pcb
	(version 20221018)
	(generator pcbnew)
	(general
    (thickness 1.7403)
  )
	(paper "A4")
	(title_block
    (title "Data Center RDIMM DDR4 Tester")
    (date "2024-09-30")
    (rev "1.2.4")
		(comment 9 "footprints 373-373 of 690")
	)
	(layers
    (0 "F.Cu" signal)
    (1 "In1.Cu" power)
    (2 "In2.Cu" signal)
    (3 "In3.Cu" power)
    (4 "In4.Cu" power)
    (5 "In5.Cu" signal)
    (6 "In6.Cu" power)
    (7 "In7.Cu" signal)
    (8 "In8.Cu" power)
    (9 "In9.Cu" signal)
    (10 "In10.Cu" power)
    (31 "B.Cu" signal)
    (32 "B.Adhes" user "B.Adhesive")
    (33 "F.Adhes" user "F.Adhesive")
    (34 "B.Paste" user)
    (35 "F.Paste" user)
    (36 "B.SilkS" user "B.Silkscreen")
    (37 "F.SilkS" user "F.Silkscreen")
    (38 "B.Mask" user)
    (39 "F.Mask" user)
    (40 "Dwgs.User" user "User.Drawings")
    (41 "Cmts.User" user "User.Comments")
    (42 "Eco1.User" user "User.Eco1")
    (43 "Eco2.User" user "User.Eco2")
    (44 "Edge.Cuts" user)
    (45 "Margin" user)
    (46 "B.CrtYd" user "B.Courtyard")
    (47 "F.CrtYd" user "F.Courtyard")
    (48 "B.Fab" user)
    (49 "F.Fab" user)
  )
	(footprint "data-center-rdimm-ddr4-tester-footprints:QFN-56-1EP_8x8mm_P0.5mm" (layer "F.Cu")
    (at 140.78 107.12 90)
    (descr "QFN 56 Pin")
    (tags "QFN")
    (property "Author" "Antmicro")
    (property "License" "Apache-2.0")
    (property "MPN" "FT4232H-56Q-REEL")
    (property "Manufacturer" "FTDI Chip")
    (property "Sheetfile" "interfaces.kicad_sch")
    (property "Sheetname" "Interfaces")
    (property "ki_description" "Interface Bridges, USB to UART, MPSSE, 1.62 V, 1.98 V, VQFN, 56 Pins, -40 °C")
    (property "ki_keywords" "SMT, INTERFACE, IC, CONTROLLER, USB, UART, I2C, SPI, JTAG")
    (attr smd)
    (fp_text reference "U7" (at 4.25 -4.89 180) (layer "F.SilkS")
        (effects (font (size 0.7 0.7) (thickness 0.15)) (justify left bottom))
    )
    (fp_text value "FT4232H_VQFN" (at 0 5.32 90) (layer "F.Fab")
        (effects (font (size 0.7 0.7) (thickness 0.15)) (justify left bottom))
    )
    (fp_text user "Author: Antmicro" (at -4.4 8.519 90) (layer "F.Fab") hide
        (effects (font (size 0.7 0.7) (thickness 0.15)) (justify left bottom))
    )
    (fp_text user "${REFERENCE}" (at -4.4 7.32 90) (layer "F.Fab") hide
        (effects (font (size 0.7 0.7) (thickness 0.15)) (justify left bottom))
    )
    (fp_text user "License: Apache-2.0" (at -4.4 9.719 90) (layer "F.Fab") hide
        (effects (font (size 0.7 0.7) (thickness 0.15)) (justify left bottom))
    )
    (fp_line (start -4.111 -3.635) (end -4.111 -4.111)
      (stroke (width 0.15) (type solid)) (layer "F.SilkS"))
    (fp_line (start -4.111 4.11) (end -4.111 3.634)
      (stroke (width 0.15) (type solid)) (layer "F.SilkS"))
    (fp_line (start -3.635 -4.111) (end -4.111 -4.111)
      (stroke (width 0.15) (type solid)) (layer "F.SilkS"))
    (fp_line (start -3.635 4.11) (end -4.111 4.11)
      (stroke (width 0.15) (type solid)) (layer "F.SilkS"))
    (fp_line (start 3.634 -4.111) (end 4.11 -4.111)
      (stroke (width 0.15) (type solid)) (layer "F.SilkS"))
    (fp_line (start 3.634 4.11) (end 4.11 4.11)
      (stroke (width 0.15) (type solid)) (layer "F.SilkS"))
    (fp_line (start 4.11 -4.111) (end 4.11 -3.635)
      (stroke (width 0.15) (type solid)) (layer "F.SilkS"))
    (fp_line (start 4.11 4.11) (end 4.11 3.634)
      (stroke (width 0.15) (type solid)) (layer "F.SilkS"))
    (fp_circle (center -4.35 -3.6) (end -4.3 -3.6)
      (stroke (width 0.15) (type solid)) (fill solid) (layer "F.SilkS"))
    (fp_rect (start 4.4 4.4) (end -4.4 -4.4)
      (stroke (width 0.05) (type solid)) (fill none) (layer "F.CrtYd"))
    (fp_line (start -4 -3) (end -3 -4)
      (stroke (width 0.15) (type solid)) (layer "F.Fab"))
    (fp_rect (start 4 4) (end -4 -4)
      (stroke (width 0.15) (type solid)) (fill none) (layer "F.Fab"))
    (pad "" smd roundrect (at -2.101 -2.101 90) (size 1.13 1.13) (layers "F.Paste") (roundrect_rratio 0.221239))
    (pad "" smd roundrect (at -2.101 -0.7 90) (size 1.13 1.13) (layers "F.Paste") (roundrect_rratio 0.221239))
    (pad "" smd roundrect (at -2.101 0.699 90) (size 1.13 1.13) (layers "F.Paste") (roundrect_rratio 0.221239))
    (pad "" smd roundrect (at -2.101 2.1 90) (size 1.13 1.13) (layers "F.Paste") (roundrect_rratio 0.221239))
    (pad "" smd roundrect (at -0.7 -2.101 90) (size 1.13 1.13) (layers "F.Paste") (roundrect_rratio 0.221239))
    (pad "" smd roundrect (at -0.7 -0.7 90) (size 1.13 1.13) (layers "F.Paste") (roundrect_rratio 0.221239))
    (pad "" smd roundrect (at -0.7 0.699 90) (size 1.13 1.13) (layers "F.Paste") (roundrect_rratio 0.221239))
    (pad "" smd roundrect (at -0.7 2.1 90) (size 1.13 1.13) (layers "F.Paste") (roundrect_rratio 0.221239))
    (pad "" smd roundrect (at 0.699 -2.101 90) (size 1.13 1.13) (layers "F.Paste") (roundrect_rratio 0.221239))
    (pad "" smd roundrect (at 0.699 -0.7 90) (size 1.13 1.13) (layers "F.Paste") (roundrect_rratio 0.221239))
    (pad "" smd roundrect (at 0.699 0.699 90) (size 1.13 1.13) (layers "F.Paste") (roundrect_rratio 0.221239))
    (pad "" smd roundrect (at 0.699 2.1 90) (size 1.13 1.13) (layers "F.Paste") (roundrect_rratio 0.221239))
    (pad "" smd roundrect (at 2.1 -2.101 90) (size 1.13 1.13) (layers "F.Paste") (roundrect_rratio 0.221239))
    (pad "" smd roundrect (at 2.1 -0.7 90) (size 1.13 1.13) (layers "F.Paste") (roundrect_rratio 0.221239))
    (pad "" smd roundrect (at 2.1 0.699 90) (size 1.13 1.13) (layers "F.Paste") (roundrect_rratio 0.221239))
    (pad "" smd roundrect (at 2.1 2.1 90) (size 1.13 1.13) (layers "F.Paste") (roundrect_rratio 0.221239))
    (pad "1" smd roundrect (at -3.938 -3.25 90) (size 0.875 0.3) (layers "F.Cu" "F.Paste" "F.Mask") (roundrect_rratio 0.25)
      (net 673 "unconnected-(U7-EECS-Pad1)") (pinfunction "EECS") (pintype "bidirectional+no_connect"))
    (pad "2" smd roundrect (at -3.938 -2.75 90) (size 0.875 0.3) (layers "F.Cu" "F.Paste" "F.Mask") (roundrect_rratio 0.25)
      (net 145 "1V8_FT") (pinfunction "V_{CORE}") (pintype "power_in"))
    (pad "3" smd roundrect (at -3.938 -2.25 90) (size 0.875 0.3) (layers "F.Cu" "F.Paste" "F.Mask") (roundrect_rratio 0.25)
      (net 80 "Net-(U7-OSCI)") (pinfunction "OSCI") (pintype "input"))
    (pad "4" smd roundrect (at -3.938 -1.75 90) (size 0.875 0.3) (layers "F.Cu" "F.Paste" "F.Mask") (roundrect_rratio 0.25)
      (net 81 "Net-(U7-OSCO)") (pinfunction "OSCO") (pintype "output"))
    (pad "5" smd roundrect (at -3.938 -1.25 90) (size 0.875 0.3) (layers "F.Cu" "F.Paste" "F.Mask") (roundrect_rratio 0.25)
      (net 76 "Net-(U7-V_{PHY})") (pinfunction "V_{PHY}") (pintype "power_in"))
    (pad "6" smd roundrect (at -3.938 -0.75 90) (size 0.875 0.3) (layers "F.Cu" "F.Paste" "F.Mask") (roundrect_rratio 0.25)
      (net 654 "Net-(U7-REF)") (pinfunction "REF") (pintype "input"))
    (pad "7" smd roundrect (at -3.938 -0.25 90) (size 0.875 0.3) (layers "F.Cu" "F.Paste" "F.Mask") (roundrect_rratio 0.25)
      (net 11 "DBG_USB_N") (pinfunction "D-") (pintype "bidirectional"))
    (pad "8" smd roundrect (at -3.938 0.249 90) (size 0.875 0.3) (layers "F.Cu" "F.Paste" "F.Mask") (roundrect_rratio 0.25)
      (net 10 "DBG_USB_P") (pinfunction "D+") (pintype "bidirectional"))
    (pad "9" smd roundrect (at -3.938 0.749 90) (size 0.875 0.3) (layers "F.Cu" "F.Paste" "F.Mask") (roundrect_rratio 0.25)
      (net 75 "Net-(U7-V_{PLL})") (pinfunction "V_{PLL}") (pintype "power_in"))
    (pad "10" smd roundrect (at -3.938 1.249 90) (size 0.875 0.3) (layers "F.Cu" "F.Paste" "F.Mask") (roundrect_rratio 0.25)
      (net 9 "GND") (pinfunction "TEST") (pintype "input"))
    (pad "11" smd roundrect (at -3.938 1.749 90) (size 0.875 0.3) (layers "F.Cu" "F.Paste" "F.Mask") (roundrect_rratio 0.25)
      (net 657 "Net-(U7-~{RESET})") (pinfunction "~{RESET}") (pintype "input"))
    (pad "12" smd roundrect (at -3.938 2.249 90) (size 0.875 0.3) (layers "F.Cu" "F.Paste" "F.Mask") (roundrect_rratio 0.25)
      (net 593 "Net-(U7-ADBUS0)") (pinfunction "ADBUS0") (pintype "bidirectional"))
    (pad "13" smd roundrect (at -3.938 2.749 90) (size 0.875 0.3) (layers "F.Cu" "F.Paste" "F.Mask") (roundrect_rratio 0.25)
      (net 594 "Net-(U7-ADBUS1)") (pinfunction "ADBUS1") (pintype "bidirectional"))
    (pad "14" smd roundrect (at -3.938 3.249 90) (size 0.875 0.3) (layers "F.Cu" "F.Paste" "F.Mask") (roundrect_rratio 0.25)
      (net 595 "Net-(U7-ADBUS2)") (pinfunction "ADBUS2") (pintype "bidirectional"))
    (pad "15" smd roundrect (at -3.25 3.937 180) (size 0.875 0.3) (layers "F.Cu" "F.Paste" "F.Mask") (roundrect_rratio 0.25)
      (net 598 "Net-(U7-ADBUS3)") (pinfunction "ADBUS3") (pintype "bidirectional"))
    (pad "16" smd roundrect (at -2.75 3.937 180) (size 0.875 0.3) (layers "F.Cu" "F.Paste" "F.Mask") (roundrect_rratio 0.25)
      (net 143 "3V3_SYS") (pinfunction "V_{CCIO}") (pintype "power_in"))
    (pad "17" smd roundrect (at -2.25 3.937 180) (size 0.875 0.3) (layers "F.Cu" "F.Paste" "F.Mask") (roundrect_rratio 0.25)
      (net 674 "unconnected-(U7-ADBUS4-Pad17)") (pinfunction "ADBUS4") (pintype "bidirectional+no_connect"))
    (pad "18" smd roundrect (at -1.75 3.937 180) (size 0.875 0.3) (layers "F.Cu" "F.Paste" "F.Mask") (roundrect_rratio 0.25)
      (net 665 "Net-(U7-ADBUS5)") (pinfunction "ADBUS5") (pintype "bidirectional"))
    (pad "19" smd roundrect (at -1.25 3.937 180) (size 0.875 0.3) (layers "F.Cu" "F.Paste" "F.Mask") (roundrect_rratio 0.25)
      (net 675 "unconnected-(U7-ADBUS6-Pad19)") (pinfunction "ADBUS6") (pintype "bidirectional+no_connect"))
    (pad "20" smd roundrect (at -0.75 3.937 180) (size 0.875 0.3) (layers "F.Cu" "F.Paste" "F.Mask") (roundrect_rratio 0.25)
      (net 676 "unconnected-(U7-ADBUS7-Pad20)") (pinfunction "ADBUS7") (pintype "bidirectional+no_connect"))
    (pad "21" smd roundrect (at -0.25 3.937 180) (size 0.875 0.3) (layers "F.Cu" "F.Paste" "F.Mask") (roundrect_rratio 0.25)
      (net 9 "GND") (pinfunction "GND") (pintype "power_in"))
    (pad "22" smd roundrect (at 0.249 3.937 180) (size 0.875 0.3) (layers "F.Cu" "F.Paste" "F.Mask") (roundrect_rratio 0.25)
      (net 585 "Net-(U7-BDBUS0)") (pinfunction "BDBUS0") (pintype "bidirectional"))
    (pad "23" smd roundrect (at 0.749 3.937 180) (size 0.875 0.3) (layers "F.Cu" "F.Paste" "F.Mask") (roundrect_rratio 0.25)
      (net 586 "Net-(U7-BDBUS1)") (pinfunction "BDBUS1") (pintype "bidirectional"))
    (pad "24" smd roundrect (at 1.249 3.937 180) (size 0.875 0.3) (layers "F.Cu" "F.Paste" "F.Mask") (roundrect_rratio 0.25)
      (net 587 "Net-(U7-BDBUS2)") (pinfunction "BDBUS2") (pintype "bidirectional"))
    (pad "25" smd roundrect (at 1.749 3.937 180) (size 0.875 0.3) (layers "F.Cu" "F.Paste" "F.Mask") (roundrect_rratio 0.25)
      (net 588 "Net-(U7-BDBUS3)") (pinfunction "BDBUS3") (pintype "bidirectional"))
    (pad "26" smd roundrect (at 2.249 3.937 180) (size 0.875 0.3) (layers "F.Cu" "F.Paste" "F.Mask") (roundrect_rratio 0.25)
      (net 677 "unconnected-(U7-BDBUS4-Pad26)") (pinfunction "BDBUS4") (pintype "bidirectional+no_connect"))
    (pad "27" smd roundrect (at 2.749 3.937 180) (size 0.875 0.3) (layers "F.Cu" "F.Paste" "F.Mask") (roundrect_rratio 0.25)
      (net 589 "Net-(U7-BDBUS5)") (pinfunction "BDBUS5") (pintype "bidirectional"))
    (pad "28" smd roundrect (at 3.249 3.937 180) (size 0.875 0.3) (layers "F.Cu" "F.Paste" "F.Mask") (roundrect_rratio 0.25)
      (net 678 "unconnected-(U7-BDBUS6-Pad28)") (pinfunction "BDBUS6") (pintype "bidirectional+no_connect"))
    (pad "29" smd roundrect (at 3.937 3.249 90) (size 0.875 0.3) (layers "F.Cu" "F.Paste" "F.Mask") (roundrect_rratio 0.25)
      (net 679 "unconnected-(U7-BDBUS7-Pad29)") (pinfunction "BDBUS7") (pintype "bidirectional+no_connect"))
    (pad "30" smd roundrect (at 3.937 2.749 90) (size 0.875 0.3) (layers "F.Cu" "F.Paste" "F.Mask") (roundrect_rratio 0.25)
      (net 680 "unconnected-(U7-~{SUSPEND}-Pad30)") (pinfunction "~{SUSPEND}") (pintype "output+no_connect"))
    (pad "31" smd roundrect (at 3.937 2.249 90) (size 0.875 0.3) (layers "F.Cu" "F.Paste" "F.Mask") (roundrect_rratio 0.25)
      (net 145 "1V8_FT") (pinfunction "V_{CORE}") (pintype "passive"))
    (pad "32" smd roundrect (at 3.937 1.749 90) (size 0.875 0.3) (layers "F.Cu" "F.Paste" "F.Mask") (roundrect_rratio 0.25)
      (net 590 "Net-(U7-CDBUS0)") (pinfunction "CDBUS0") (pintype "bidirectional"))
    (pad "33" smd roundrect (at 3.937 1.249 90) (size 0.875 0.3) (layers "F.Cu" "F.Paste" "F.Mask") (roundrect_rratio 0.25)
      (net 591 "Net-(U7-CDBUS1)") (pinfunction "CDBUS1") (pintype "bidirectional"))
    (pad "34" smd roundrect (at 3.937 0.749 90) (size 0.875 0.3) (layers "F.Cu" "F.Paste" "F.Mask") (roundrect_rratio 0.25)
      (net 681 "unconnected-(U7-CDBUS2-Pad34)") (pinfunction "CDBUS2") (pintype "bidirectional+no_connect"))
    (pad "35" smd roundrect (at 3.937 0.249 90) (size 0.875 0.3) (layers "F.Cu" "F.Paste" "F.Mask") (roundrect_rratio 0.25)
      (net 682 "unconnected-(U7-CDBUS3-Pad35)") (pinfunction "CDBUS3") (pintype "bidirectional+no_connect"))
    (pad "36" smd roundrect (at 3.937 -0.25 90) (size 0.875 0.3) (layers "F.Cu" "F.Paste" "F.Mask") (roundrect_rratio 0.25)
      (net 143 "3V3_SYS") (pinfunction "V_{CCIO}") (pintype "passive"))
    (pad "37" smd roundrect (at 3.937 -0.75 90) (size 0.875 0.3) (layers "F.Cu" "F.Paste" "F.Mask") (roundrect_rratio 0.25)
      (net 683 "unconnected-(U7-CDBUS4-Pad37)") (pinfunction "CDBUS4") (pintype "bidirectional+no_connect"))
    (pad "38" smd roundrect (at 3.937 -1.25 90) (size 0.875 0.3) (layers "F.Cu" "F.Paste" "F.Mask") (roundrect_rratio 0.25)
      (net 684 "unconnected-(U7-CDBUS5-Pad38)") (pinfunction "CDBUS5") (pintype "bidirectional+no_connect"))
    (pad "39" smd roundrect (at 3.937 -1.75 90) (size 0.875 0.3) (layers "F.Cu" "F.Paste" "F.Mask") (roundrect_rratio 0.25)
      (net 685 "unconnected-(U7-CDBUS6-Pad39)") (pinfunction "CDBUS6") (pintype "bidirectional+no_connect"))
    (pad "40" smd roundrect (at 3.937 -2.25 90) (size 0.875 0.3) (layers "F.Cu" "F.Paste" "F.Mask") (roundrect_rratio 0.25)
      (net 686 "unconnected-(U7-CDBUS7-Pad40)") (pinfunction "CDBUS7") (pintype "bidirectional+no_connect"))
    (pad "41" smd roundrect (at 3.937 -2.75 90) (size 0.875 0.3) (layers "F.Cu" "F.Paste" "F.Mask") (roundrect_rratio 0.25)
      (net 9 "GND") (pinfunction "GND") (pintype "passive"))
    (pad "42" smd roundrect (at 3.937 -3.25 90) (size 0.875 0.3) (layers "F.Cu" "F.Paste" "F.Mask") (roundrect_rratio 0.25)
      (net 592 "Net-(U7-DDBUS0)") (pinfunction "DDBUS0") (pintype "bidirectional"))
    (pad "43" smd roundrect (at 3.249 -3.938 180) (size 0.875 0.3) (layers "F.Cu" "F.Paste" "F.Mask") (roundrect_rratio 0.25)
      (net 145 "1V8_FT") (pinfunction "V_{REGOUT}") (pintype "power_out"))
    (pad "44" smd roundrect (at 2.749 -3.938 180) (size 0.875 0.3) (layers "F.Cu" "F.Paste" "F.Mask") (roundrect_rratio 0.25)
      (net 143 "3V3_SYS") (pinfunction "V_{REGIN}") (pintype "power_in"))
    (pad "45" smd roundrect (at 2.249 -3.938 180) (size 0.875 0.3) (layers "F.Cu" "F.Paste" "F.Mask") (roundrect_rratio 0.25)
      (net 9 "GND") (pinfunction "GND") (pintype "passive"))
    (pad "46" smd roundrect (at 1.749 -3.938 180) (size 0.875 0.3) (layers "F.Cu" "F.Paste" "F.Mask") (roundrect_rratio 0.25)
      (net 602 "Net-(U7-DDBUS1)") (pinfunction "DDBUS1") (pintype "bidirectional"))
    (pad "47" smd roundrect (at 1.249 -3.938 180) (size 0.875 0.3) (layers "F.Cu" "F.Paste" "F.Mask") (roundrect_rratio 0.25)
      (net 687 "unconnected-(U7-DDBUS2-Pad47)") (pinfunction "DDBUS2") (pintype "bidirectional+no_connect"))
    (pad "48" smd roundrect (at 0.749 -3.938 180) (size 0.875 0.3) (layers "F.Cu" "F.Paste" "F.Mask") (roundrect_rratio 0.25)
      (net 688 "unconnected-(U7-DDBUS3-Pad48)") (pinfunction "DDBUS3") (pintype "bidirectional+no_connect"))
    (pad "49" smd roundrect (at 0.249 -3.938 180) (size 0.875 0.3) (layers "F.Cu" "F.Paste" "F.Mask") (roundrect_rratio 0.25)
      (net 689 "unconnected-(U7-DDBUS4-Pad49)") (pinfunction "DDBUS4") (pintype "bidirectional+no_connect"))
    (pad "50" smd roundrect (at -0.25 -3.938 180) (size 0.875 0.3) (layers "F.Cu" "F.Paste" "F.Mask") (roundrect_rratio 0.25)
      (net 143 "3V3_SYS") (pinfunction "V_{CCIO}") (pintype "passive"))
    (pad "51" smd roundrect (at -0.75 -3.938 180) (size 0.875 0.3) (layers "F.Cu" "F.Paste" "F.Mask") (roundrect_rratio 0.25)
      (net 690 "unconnected-(U7-DDBUS5-Pad51)") (pinfunction "DDBUS5") (pintype "bidirectional+no_connect"))
    (pad "52" smd roundrect (at -1.25 -3.938 180) (size 0.875 0.3) (layers "F.Cu" "F.Paste" "F.Mask") (roundrect_rratio 0.25)
      (net 691 "unconnected-(U7-DDBUS6-Pad52)") (pinfunction "DDBUS6") (pintype "bidirectional+no_connect"))
    (pad "53" smd roundrect (at -1.75 -3.938 180) (size 0.875 0.3) (layers "F.Cu" "F.Paste" "F.Mask") (roundrect_rratio 0.25)
      (net 692 "unconnected-(U7-DDBUS7-Pad53)") (pinfunction "DDBUS7") (pintype "bidirectional+no_connect"))
    (pad "54" smd roundrect (at -2.25 -3.938 180) (size 0.875 0.3) (layers "F.Cu" "F.Paste" "F.Mask") (roundrect_rratio 0.25)
      (net 693 "unconnected-(U7-~{PWR_{EN}}-Pad54)") (pinfunction "~{PWR_{EN}}") (pintype "output+no_connect"))
    (pad "55" smd roundrect (at -2.75 -3.938 180) (size 0.875 0.3) (layers "F.Cu" "F.Paste" "F.Mask") (roundrect_rratio 0.25)
      (net 694 "unconnected-(U7-EEDATA-Pad55)") (pinfunction "EEDATA") (pintype "bidirectional+no_connect"))
    (pad "56" smd roundrect (at -3.25 -3.938 180) (size 0.875 0.3) (layers "F.Cu" "F.Paste" "F.Mask") (roundrect_rratio 0.25)
      (net 695 "unconnected-(U7-EECLK-Pad56)") (pinfunction "EECLK") (pintype "output+no_connect"))
    (pad "57" smd rect (at 0 0 90) (size 5.9 5.9) (layers "F.Cu" "F.Mask")
      (net 9 "GND") (pinfunction "GND") (pintype "passive"))
  )
)
